# T6G (Grand Teton) — schematic netlist excerpt (pin names and nets, part order shuffled) for the footprints in the layout excerpt that follows; sources: Cadence DE-HDL packaged netlist, KiCad conversion of 04192023_DAF0TMB3IC0_F0TG_MB_C_brd_V02_OCP.brd

U212  74LV4052PW  IC  pkg TSSOP16_0-65_5X4-4XH  page 171
  \2y0\  = TP_JTAG_SCM_SLOT3_R_TDO
  \2y2\  = JTAG_SCM_PLD_R_TDO
  \2z\  = JTAG_SCM_TDO
  \2y3\  = JTAG_SCM_PLD_R_TDO
  \2y1\  = JTAG_SCM_MUX_R_TDO
  E_N  = U212_EN_N
  VEE  = GND
  GND  = GND
  S1  = SCM_JTAG_MUX_S1
  S0  = SCM_JTAG_MUX_S0_R2
  \1y3\  = JTAG_SCM_PLD_R_TDI
  \1y0\  = TP_JTAG_SCM_SLOT3_R_TDI
  \1z\  = JTAG_SCM_TDI
  \1y1\  = JTAG_SCM_MUX_R_TDI
  \1y2\  = JTAG_SCM_PLD_R_TDI
  VCC  = P3V3_AUX

(kicad_pcb
	(version 20260206)
	(generator "pcbnew")
	(generator_version "10.0")
	(general
		(thickness 1.6)
		(legacy_teardrops no)
	)
	(paper "A4")
	(title_block
		(title "04192023_DAF0TMB3IC0_F0TG_MB_C_brd_V02_OCP.brd")
		(comment 1 "Grand Teton / footprints 754-754 of 8354")
	)
	(layers
		(0 "F.Cu" signal "TOP")
		(4 "In1.Cu" signal "GND")
		(6 "In2.Cu" signal "IN1")
		(8 "In3.Cu" signal "GND1")
		(10 "In4.Cu" signal "IN2")
		(12 "In5.Cu" signal "GND2")
		(14 "In6.Cu" signal "IN3")
		(16 "In7.Cu" signal "GND3")
		(18 "In8.Cu" signal "VCC")
		(20 "In9.Cu" signal "VCC1")
		(22 "In10.Cu" signal "GND4")
		(24 "In11.Cu" signal "IN4")
		(26 "In12.Cu" signal "GND5")
		(28 "In13.Cu" signal "IN5")
		(30 "In14.Cu" signal "GND6")
		(32 "In15.Cu" signal "IN6")
		(34 "In16.Cu" signal "GND7")
		(2 "B.Cu" signal "BOTTOM")
		(9 "F.Adhes" user "F.Adhesive")
		(11 "B.Adhes" user "B.Adhesive")
		(13 "F.Paste" user "Package Geometry/Pastemask Top")
		(15 "B.Paste" user "Package Geometry/Pastemask Bottom")
		(5 "F.SilkS" user "Ref Des/Silkscreen Top")
		(7 "B.SilkS" user "Ref Des/Silkscreen Bottom")
		(1 "F.Mask" user "Board Geometry/Soldermask Top")
		(3 "B.Mask" user "Board Geometry/Soldermask Bottom")
		(17 "Dwgs.User" user "User.Drawings")
		(19 "Cmts.User" user "User.Comments")
		(21 "Eco1.User" user "User.Eco1")
		(23 "Eco2.User" user "User.Eco2")
		(25 "Edge.Cuts" user "Board Geometry/Outline")
		(27 "Margin" user)
		(31 "F.CrtYd" user "Package Geometry/Place Bound Top")
		(29 "B.CrtYd" user "Package Geometry/Place Bound Bottom")
		(35 "F.Fab" user "Ref Des/Assembly Top")
		(33 "B.Fab" user "Ref Des/Assembly Bottom")
	)
	(footprint ""
		(layer "F.Cu")
		(at 131.689094 -59.50712)
		(property "Reference" "U212"
			(at -0.851662 -3.495802 0)
			(unlocked yes)
			(layer "F.SilkS")
			(effects
				(font
					(size 0.7874 0.5842)
					(thickness 0.1524)
				)
				(justify left)
			)
		)
		(property "Value" ""
			(at 0 0 0)
			(layer "F.Fab")
			(effects
				(font
					(size 1.27 1.27)
				)
			)
		)
		(duplicate_pad_numbers_are_jumpers no)
		(fp_line
			(start -2.112264 -2.549906)
			(end -0.704088 -2.549906)
			(stroke
				(width 0.1524)
				(type default)
			)
			(layer "F.SilkS")
		)
		(fp_line
			(start -2.112264 2.549906)
			(end -2.112264 -2.549906)
			(stroke
				(width 0.1524)
				(type default)
			)
			(layer "F.SilkS")
		)
		(fp_line
			(start -0.704088 -2.549906)
			(end 0 -1.845818)
			(stroke
				(width 0.1524)
				(type default)
			)
			(layer "F.SilkS")
		)
		(fp_line
			(start 0 -1.845818)
			(end 0.704088 -2.549906)
			(stroke
				(width 0.1524)
				(type default)
			)
			(layer "F.SilkS")
		)
		(fp_line
			(start 0.704088 -2.549906)
			(end 2.112264 -2.549906)
			(stroke
				(width 0.1524)
				(type default)
			)
			(layer "F.SilkS")
		)
		(fp_line
			(start 2.112264 -2.549906)
			(end 2.112264 2.549906)
			(stroke
				(width 0.1524)
				(type default)
			)
			(layer "F.SilkS")
		)
		(fp_line
			(start 2.112264 2.549906)
			(end -2.112264 2.549906)
			(stroke
				(width 0.1524)
				(type default)
			)
			(layer "F.SilkS")
		)
		(fp_poly
			(pts
				(xy -4.215892 -4.104386) (xy -4.821174 -3.288538) (xy -3.702558 -3.09118)
			)
			(stroke
				(width 0)
				(type default)
			)
			(fill yes)
			(layer "F.SilkS")
		)
		(fp_line
			(start -2.249932 -2.549906)
			(end 2.249932 -2.549906)
			(stroke
				(width 0.1)
				(type default)
			)
			(layer "F.Fab")
		)
		(fp_line
			(start -2.249932 2.549906)
			(end -2.249932 -2.549906)
			(stroke
				(width 0.1)
				(type default)
			)
			(layer "F.Fab")
		)
		(fp_line
			(start 2.249932 -2.549906)
			(end 2.249932 2.549906)
			(stroke
				(width 0.1)
				(type default)
			)
			(layer "F.Fab")
		)
		(fp_line
			(start 2.249932 2.549906)
			(end -2.249932 2.549906)
			(stroke
				(width 0.1)
				(type default)
			)
			(layer "F.Fab")
		)
		(fp_poly
			(pts
				(xy -4.917186 -2.8829) (xy -4.917186 -1.8669) (xy -3.901186 -2.3749)
			)
			(stroke
				(width 0)
				(type default)
			)
			(fill yes)
			(layer "F.Fab")
		)
		(pad "1" smd rect
			(at -2.925064 -2.3749 270)
			(size 0.6096 1.3716)
			(layers "F.Cu" "F.Mask" "F.Paste")
			(net "TP_JTAG_SCM_SLOT3_R_TDO")
		)
		(pad "2" smd rect
			(at -2.925064 -1.625092 270)
			(size 0.4064 1.3716)
			(layers "F.Cu" "F.Mask" "F.Paste")
			(net "JTAG_SCM_PLD_R_TDO")
		)
		(pad "3" smd rect
			(at -2.925064 -0.975106 270)
			(size 0.4064 1.3716)
			(layers "F.Cu" "F.Mask" "F.Paste")
			(net "JTAG_SCM_TDO")
		)
		(pad "4" smd rect
			(at -2.925064 -0.32512 270)
			(size 0.4064 1.3716)
			(layers "F.Cu" "F.Mask" "F.Paste")
			(net "JTAG_SCM_PLD_R_TDO")
		)
		(pad "5" smd rect
			(at -2.925064 0.32512 270)
			(size 0.4064 1.3716)
			(layers "F.Cu" "F.Mask" "F.Paste")
			(net "JTAG_SCM_MUX_R_TDO")
		)
		(pad "6" smd rect
			(at -2.925064 0.975106 270)
			(size 0.4064 1.3716)
			(layers "F.Cu" "F.Mask" "F.Paste")
			(net "U212_EN_N")
		)
		(pad "7" smd rect
			(at -2.925064 1.625092 270)
			(size 0.4064 1.3716)
			(layers "F.Cu" "F.Mask" "F.Paste")
			(net "GND")
		)
		(pad "8" smd rect
			(at -2.925064 2.3749 270)
			(size 0.6096 1.3716)
			(layers "F.Cu" "F.Mask" "F.Paste")
			(net "GND")
		)
		(pad "9" smd rect
			(at 2.925064 2.3749 270)
			(size 0.6096 1.3716)
			(layers "F.Cu" "F.Mask" "F.Paste")
			(net "SCM_JTAG_MUX_S1")
		)
		(pad "10" smd rect
			(at 2.925064 1.625092 270)
			(size 0.4064 1.3716)
			(layers "F.Cu" "F.Mask" "F.Paste")
			(net "SCM_JTAG_MUX_S0_R2")
		)
		(pad "11" smd rect
			(at 2.925064 0.975106 270)
			(size 0.4064 1.3716)
			(layers "F.Cu" "F.Mask" "F.Paste")
			(net "JTAG_SCM_PLD_R_TDI")
		)
		(pad "12" smd rect
			(at 2.925064 0.32512 270)
			(size 0.4064 1.3716)
			(layers "F.Cu" "F.Mask" "F.Paste")
			(net "TP_JTAG_SCM_SLOT3_R_TDI")
		)
		(pad "13" smd rect
			(at 2.925064 -0.32512 270)
			(size 0.4064 1.3716)
			(layers "F.Cu" "F.Mask" "F.Paste")
			(net "JTAG_SCM_TDI")
		)
		(pad "14" smd rect
			(at 2.925064 -0.975106 270)
			(size 0.4064 1.3716)
			(layers "F.Cu" "F.Mask" "F.Paste")
			(net "JTAG_SCM_MUX_R_TDI")
		)
		(pad "15" smd rect
			(at 2.925064 -1.625092 270)
			(size 0.4064 1.3716)
			(layers "F.Cu" "F.Mask" "F.Paste")
			(net "JTAG_SCM_PLD_R_TDI")
		)
		(pad "16" smd rect
			(at 2.925064 -2.3749 270)
			(size 0.6096 1.3716)
			(layers "F.Cu" "F.Mask" "F.Paste")
			(net "P3V3_AUX")
		)
	)
)
